FILE_TYPE = MACRO_DRAWING;
SET COLOR_WIRE YELLOW;
SET COLOR_PROP ORANGE;
SET COLOR_DOT WHITE;
SET COLOR_ARC YELLOW;
SET COLOR_BODY GREEN;
SET COLOR_NOTE PURPLE;
SET PROP_DISPLAY VALUE;
SET PAGE_NUMBER P60;
FORCEADD UNIVERSAL_GND..1
R 1
(-1075 4675);
FORCEPROP 3 LASTPIN (-1125 4675) SIG_NAME GND\g
J 0
(-1115 4685);
DISPLAY 0.659574 (-1115 4685);
PAINT MONO (-1115 4685);
DISPLAY INVISIBLE (-1115 4685);
FORCEPROP 2 LAST CDS_LIB pure_quanta_power
J 0
(-1075 4675);
DISPLAY INVISIBLE (-1075 4675);
FORCEPROP 1 LAST HDL_POWER GND
R 1
J 1
(-1000 4700);
DISPLAY 0.872340 (-1000 4700);
PAINT GREEN (-1000 4700);
DISPLAY INVISIBLE (-1000 4700);
FORCEPROP 1 LAST PATH I1
R 1
J 0
(-1075 4750);
DISPLAY 0.872340 (-1075 4750);
PAINT AQUA (-1075 4750);
DISPLAY INVISIBLE (-1075 4750);
FORCEADD UNIVERSAL_GND..1
R 1
(-1650 3225);
FORCEPROP 3 LASTPIN (-1700 3225) SIG_NAME GND\g
J 0
(-1690 3235);
DISPLAY 0.659574 (-1690 3235);
PAINT MONO (-1690 3235);
DISPLAY INVISIBLE (-1690 3235);
FORCEPROP 2 LAST CDS_LIB pure_quanta_power
J 0
(-1650 3225);
DISPLAY INVISIBLE (-1650 3225);
FORCEPROP 1 LAST HDL_POWER GND
R 1
J 1
(-1575 3250);
DISPLAY 0.872340 (-1575 3250);
PAINT GREEN (-1575 3250);
DISPLAY INVISIBLE (-1575 3250);
FORCEPROP 1 LAST PATH I2
R 1
J 0
(-1650 3300);
DISPLAY 0.872340 (-1650 3300);
PAINT AQUA (-1650 3300);
DISPLAY INVISIBLE (-1650 3300);
FORCEADD GENOA_SP5..40
R 1
(-4525 3950);
FORCEPROP 1 LAST LOCATION U26
R 1
J 0
(-8181 3555);
DISPLAY 0.489362 (-8181 3555);
PAINT SKYBLUE (-8181 3555);
FORCEPROP 0 LAST $SEC 40
R 1
J 0
(-1175 4525);
DISPLAY 0.680851 (-1175 4525);
PAINT MONO (-1175 4525);
DISPLAY INVISIBLE (-1175 4525);
FORCEPROP 0 LAST CDS_SEC 40
R 1
J 0
(-1175 4525);
DISPLAY 1.021277 (-1175 4525);
DISPLAY INVISIBLE (-1175 4525);
FORCEPROP 0 LASTPIN (-2425 4500) $PN AA42
R 1
J 0
(-2435 4510);
DISPLAY 0.489362 (-2435 4510);
PAINT MONO (-2435 4510);
FORCEPROP 0 LASTPIN (-2375 4500) $PN AA72
R 1
J 0
(-2385 4510);
DISPLAY 0.489362 (-2385 4510);
PAINT MONO (-2385 4510);
FORCEPROP 0 LASTPIN (-2325 4500) $PN AD31
R 1
J 0
(-2335 4510);
DISPLAY 0.489362 (-2335 4510);
PAINT MONO (-2335 4510);
FORCEPROP 0 LASTPIN (-2275 4500) $PN AE4
R 1
J 0
(-2285 4510);
DISPLAY 0.489362 (-2285 4510);
PAINT MONO (-2285 4510);
FORCEPROP 0 LASTPIN (-2225 4500) $PN AH33
R 1
J 0
(-2235 4510);
DISPLAY 0.489362 (-2235 4510);
PAINT MONO (-2235 4510);
FORCEPROP 0 LASTPIN (-2175 4500) $PN AJ13
R 1
J 0
(-2185 4510);
DISPLAY 0.489362 (-2185 4510);
PAINT MONO (-2185 4510);
FORCEPROP 0 LASTPIN (-2125 4500) $PN AM37
R 1
J 0
(-2135 4510);
DISPLAY 0.489362 (-2135 4510);
PAINT MONO (-2135 4510);
FORCEPROP 0 LASTPIN (-2075 4500) $PN AN20
R 1
J 0
(-2085 4510);
DISPLAY 0.489362 (-2085 4510);
PAINT MONO (-2085 4510);
FORCEPROP 0 LASTPIN (-2025 4500) $PN BV42
R 1
J 0
(-2035 4510);
DISPLAY 0.489362 (-2035 4510);
PAINT MONO (-2035 4510);
FORCEPROP 0 LASTPIN (-1975 4500) $PN BW25
R 1
J 0
(-1985 4510);
DISPLAY 0.489362 (-1985 4510);
PAINT MONO (-1985 4510);
FORCEPROP 0 LASTPIN (-1925 4500) $PN CB44
R 1
J 0
(-1935 4510);
DISPLAY 0.489362 (-1935 4510);
PAINT MONO (-1935 4510);
FORCEPROP 0 LASTPIN (-1875 4500) $PN CC22
R 1
J 0
(-1885 4510);
DISPLAY 0.489362 (-1885 4510);
PAINT MONO (-1885 4510);
FORCEPROP 0 LASTPIN (-1825 4500) $PN CF46
R 1
J 0
(-1835 4510);
DISPLAY 0.489362 (-1835 4510);
PAINT MONO (-1835 4510);
FORCEPROP 0 LASTPIN (-1775 4500) $PN CG42
R 1
J 0
(-1785 4510);
DISPLAY 0.489362 (-1785 4510);
PAINT MONO (-1785 4510);
FORCEPROP 0 LASTPIN (-1725 4500) $PN CK10
R 1
J 0
(-1735 4510);
DISPLAY 0.489362 (-1735 4510);
PAINT MONO (-1735 4510);
FORCEPROP 0 LASTPIN (-1675 4500) $PN CK31
R 1
J 0
(-1685 4510);
DISPLAY 0.489362 (-1685 4510);
PAINT MONO (-1685 4510);
FORCEPROP 0 LASTPIN (-1625 4500) $PN CM50
R 1
J 0
(-1635 4510);
DISPLAY 0.489362 (-1635 4510);
PAINT MONO (-1635 4510);
FORCEPROP 0 LASTPIN (-1575 4500) $PN CN54
R 1
J 0
(-1585 4510);
DISPLAY 0.489362 (-1585 4510);
PAINT MONO (-1585 4510);
FORCEPROP 0 LASTPIN (-1525 4500) $PN CT52
R 1
J 0
(-1535 4510);
DISPLAY 0.489362 (-1535 4510);
PAINT MONO (-1535 4510);
FORCEPROP 0 LASTPIN (-1475 4500) $PN CU58
R 1
J 0
(-1485 4510);
DISPLAY 0.489362 (-1485 4510);
PAINT MONO (-1485 4510);
FORCEPROP 0 LASTPIN (-1425 4500) $PN CY57
R 1
J 0
(-1435 4510);
DISPLAY 0.489362 (-1435 4510);
PAINT MONO (-1435 4510);
FORCEPROP 0 LASTPIN (-1375 4500) $PN DA56
R 1
J 0
(-1385 4510);
DISPLAY 0.489362 (-1385 4510);
PAINT MONO (-1385 4510);
FORCEPROP 0 LASTPIN (-7775 3400) $PN DA72
R 1
J 2
(-7785 3390);
DISPLAY 0.489362 (-7785 3390);
PAINT MONO (-7785 3390);
FORCEPROP 0 LASTPIN (-7725 3400) $PN DA75
R 1
J 2
(-7735 3390);
DISPLAY 0.489362 (-7735 3390);
PAINT MONO (-7735 3390);
FORCEPROP 0 LASTPIN (-7675 3400) $PN DB3
R 1
J 2
(-7685 3390);
DISPLAY 0.489362 (-7685 3390);
PAINT MONO (-7685 3390);
FORCEPROP 0 LASTPIN (-7625 3400) $PN DB8
R 1
J 2
(-7635 3390);
DISPLAY 0.489362 (-7635 3390);
PAINT MONO (-7635 3390);
FORCEPROP 0 LASTPIN (-7575 3400) $PN DB10
R 1
J 2
(-7585 3390);
DISPLAY 0.489362 (-7585 3390);
PAINT MONO (-7585 3390);
FORCEPROP 0 LASTPIN (-7525 3400) $PN DB15
R 1
J 2
(-7535 3390);
DISPLAY 0.489362 (-7535 3390);
PAINT MONO (-7535 3390);
FORCEPROP 0 LASTPIN (-7475 3400) $PN DB17
R 1
J 2
(-7485 3390);
DISPLAY 0.489362 (-7485 3390);
PAINT MONO (-7485 3390);
FORCEPROP 0 LASTPIN (-7425 3400) $PN DB22
R 1
J 2
(-7435 3390);
DISPLAY 0.489362 (-7435 3390);
PAINT MONO (-7435 3390);
FORCEPROP 0 LASTPIN (-7375 3400) $PN DB25
R 1
J 2
(-7385 3390);
DISPLAY 0.489362 (-7385 3390);
PAINT MONO (-7385 3390);
FORCEPROP 0 LASTPIN (-7325 3400) $PN DB28
R 1
J 2
(-7335 3390);
DISPLAY 0.489362 (-7335 3390);
PAINT MONO (-7335 3390);
FORCEPROP 0 LASTPIN (-7275 3400) $PN DB31
R 1
J 2
(-7285 3390);
DISPLAY 0.489362 (-7285 3390);
PAINT MONO (-7285 3390);
FORCEPROP 0 LASTPIN (-7225 3400) $PN DB34
R 1
J 2
(-7235 3390);
DISPLAY 0.489362 (-7235 3390);
PAINT MONO (-7235 3390);
FORCEPROP 0 LASTPIN (-7175 3400) $PN DB37
R 1
J 2
(-7185 3390);
DISPLAY 0.489362 (-7185 3390);
PAINT MONO (-7185 3390);
FORCEPROP 0 LASTPIN (-7125 3400) $PN DB39
R 1
J 2
(-7135 3390);
DISPLAY 0.489362 (-7135 3390);
PAINT MONO (-7135 3390);
FORCEPROP 0 LASTPIN (-7075 3400) $PN DB42
R 1
J 2
(-7085 3390);
DISPLAY 0.489362 (-7085 3390);
PAINT MONO (-7085 3390);
FORCEPROP 0 LASTPIN (-7025 3400) $PN DB45
R 1
J 2
(-7035 3390);
DISPLAY 0.489362 (-7035 3390);
PAINT MONO (-7035 3390);
FORCEPROP 0 LASTPIN (-6975 3400) $PN DB48
R 1
J 2
(-6985 3390);
DISPLAY 0.489362 (-6985 3390);
PAINT MONO (-6985 3390);
FORCEPROP 0 LASTPIN (-6925 3400) $PN DB51
R 1
J 2
(-6935 3390);
DISPLAY 0.489362 (-6935 3390);
PAINT MONO (-6935 3390);
FORCEPROP 0 LASTPIN (-6875 3400) $PN DB54
R 1
J 2
(-6885 3390);
DISPLAY 0.489362 (-6885 3390);
PAINT MONO (-6885 3390);
FORCEPROP 0 LASTPIN (-6825 3400) $PN DB59
R 1
J 2
(-6835 3390);
DISPLAY 0.489362 (-6835 3390);
PAINT MONO (-6835 3390);
FORCEPROP 0 LASTPIN (-6775 3400) $PN DB61
R 1
J 2
(-6785 3390);
DISPLAY 0.489362 (-6785 3390);
PAINT MONO (-6785 3390);
FORCEPROP 0 LASTPIN (-6725 3400) $PN DB66
R 1
J 2
(-6735 3390);
DISPLAY 0.489362 (-6735 3390);
PAINT MONO (-6735 3390);
FORCEPROP 0 LASTPIN (-6675 3400) $PN DB68
R 1
J 2
(-6685 3390);
DISPLAY 0.489362 (-6685 3390);
PAINT MONO (-6685 3390);
FORCEPROP 0 LASTPIN (-6625 3400) $PN DB73
R 1
J 2
(-6635 3390);
DISPLAY 0.489362 (-6635 3390);
PAINT MONO (-6635 3390);
FORCEPROP 0 LASTPIN (-6575 3400) $PN DC1
R 1
J 2
(-6585 3390);
DISPLAY 0.489362 (-6585 3390);
PAINT MONO (-6585 3390);
FORCEPROP 0 LASTPIN (-6525 3400) $PN DC4
R 1
J 2
(-6535 3390);
DISPLAY 0.489362 (-6535 3390);
PAINT MONO (-6535 3390);
FORCEPROP 0 LASTPIN (-6475 3400) $PN DC6
R 1
J 2
(-6485 3390);
DISPLAY 0.489362 (-6485 3390);
PAINT MONO (-6485 3390);
FORCEPROP 0 LASTPIN (-6425 3400) $PN DC8
R 1
J 2
(-6435 3390);
DISPLAY 0.489362 (-6435 3390);
PAINT MONO (-6435 3390);
FORCEPROP 0 LASTPIN (-6375 3400) $PN DC11
R 1
J 2
(-6385 3390);
DISPLAY 0.489362 (-6385 3390);
PAINT MONO (-6385 3390);
FORCEPROP 0 LASTPIN (-6325 3400) $PN DC13
R 1
J 2
(-6335 3390);
DISPLAY 0.489362 (-6335 3390);
PAINT MONO (-6335 3390);
FORCEPROP 0 LASTPIN (-6275 3400) $PN DC15
R 1
J 2
(-6285 3390);
DISPLAY 0.489362 (-6285 3390);
PAINT MONO (-6285 3390);
FORCEPROP 0 LASTPIN (-6225 3400) $PN DC18
R 1
J 2
(-6235 3390);
DISPLAY 0.489362 (-6235 3390);
PAINT MONO (-6235 3390);
FORCEPROP 0 LASTPIN (-6175 3400) $PN DC20
R 1
J 2
(-6185 3390);
DISPLAY 0.489362 (-6185 3390);
PAINT MONO (-6185 3390);
FORCEPROP 0 LASTPIN (-6125 3400) $PN DC22
R 1
J 2
(-6135 3390);
DISPLAY 0.489362 (-6135 3390);
PAINT MONO (-6135 3390);
FORCEPROP 0 LASTPIN (-6075 3400) $PN DC25
R 1
J 2
(-6085 3390);
DISPLAY 0.489362 (-6085 3390);
PAINT MONO (-6085 3390);
FORCEPROP 0 LASTPIN (-6025 3400) $PN DC28
R 1
J 2
(-6035 3390);
DISPLAY 0.489362 (-6035 3390);
PAINT MONO (-6035 3390);
FORCEPROP 0 LASTPIN (-5975 3400) $PN DC31
R 1
J 2
(-5985 3390);
DISPLAY 0.489362 (-5985 3390);
PAINT MONO (-5985 3390);
FORCEPROP 0 LASTPIN (-5925 3400) $PN DC34
R 1
J 2
(-5935 3390);
DISPLAY 0.489362 (-5935 3390);
PAINT MONO (-5935 3390);
FORCEPROP 0 LASTPIN (-5875 3400) $PN DC42
R 1
J 2
(-5885 3390);
DISPLAY 0.489362 (-5885 3390);
PAINT MONO (-5885 3390);
FORCEPROP 0 LASTPIN (-5825 3400) $PN DC45
R 1
J 2
(-5835 3390);
DISPLAY 0.489362 (-5835 3390);
PAINT MONO (-5835 3390);
FORCEPROP 0 LASTPIN (-5775 3400) $PN DC48
R 1
J 2
(-5785 3390);
DISPLAY 0.489362 (-5785 3390);
PAINT MONO (-5785 3390);
FORCEPROP 0 LASTPIN (-5725 3400) $PN DC51
R 1
J 2
(-5735 3390);
DISPLAY 0.489362 (-5735 3390);
PAINT MONO (-5735 3390);
FORCEPROP 0 LASTPIN (-5675 3400) $PN DC54
R 1
J 2
(-5685 3390);
DISPLAY 0.489362 (-5685 3390);
PAINT MONO (-5685 3390);
FORCEPROP 0 LASTPIN (-5625 3400) $PN DC56
R 1
J 2
(-5635 3390);
DISPLAY 0.489362 (-5635 3390);
PAINT MONO (-5635 3390);
FORCEPROP 0 LASTPIN (-5575 3400) $PN DC58
R 1
J 2
(-5585 3390);
DISPLAY 0.489362 (-5585 3390);
PAINT MONO (-5585 3390);
FORCEPROP 0 LASTPIN (-5525 3400) $PN DC61
R 1
J 2
(-5535 3390);
DISPLAY 0.489362 (-5535 3390);
PAINT MONO (-5535 3390);
FORCEPROP 0 LASTPIN (-5475 3400) $PN DC63
R 1
J 2
(-5485 3390);
DISPLAY 0.489362 (-5485 3390);
PAINT MONO (-5485 3390);
FORCEPROP 0 LASTPIN (-5425 3400) $PN DC65
R 1
J 2
(-5435 3390);
DISPLAY 0.489362 (-5435 3390);
PAINT MONO (-5435 3390);
FORCEPROP 0 LASTPIN (-5375 3400) $PN DC68
R 1
J 2
(-5385 3390);
DISPLAY 0.489362 (-5385 3390);
PAINT MONO (-5385 3390);
FORCEPROP 0 LASTPIN (-5325 3400) $PN DC70
R 1
J 2
(-5335 3390);
DISPLAY 0.489362 (-5335 3390);
PAINT MONO (-5335 3390);
FORCEPROP 0 LASTPIN (-5275 3400) $PN DC72
R 1
J 2
(-5285 3390);
DISPLAY 0.489362 (-5285 3390);
PAINT MONO (-5285 3390);
FORCEPROP 0 LASTPIN (-5225 3400) $PN DC75
R 1
J 2
(-5235 3390);
DISPLAY 0.489362 (-5235 3390);
PAINT MONO (-5235 3390);
FORCEPROP 0 LASTPIN (-5175 3400) $PN DD3
R 1
J 2
(-5185 3390);
DISPLAY 0.489362 (-5185 3390);
PAINT MONO (-5185 3390);
FORCEPROP 0 LASTPIN (-5125 3400) $PN DD5
R 1
J 2
(-5135 3390);
DISPLAY 0.489362 (-5135 3390);
PAINT MONO (-5135 3390);
FORCEPROP 0 LASTPIN (-5075 3400) $PN DD8
R 1
J 2
(-5085 3390);
DISPLAY 0.489362 (-5085 3390);
PAINT MONO (-5085 3390);
FORCEPROP 0 LASTPIN (-5025 3400) $PN DD10
R 1
J 2
(-5035 3390);
DISPLAY 0.489362 (-5035 3390);
PAINT MONO (-5035 3390);
FORCEPROP 0 LASTPIN (-4975 3400) $PN DD12
R 1
J 2
(-4985 3390);
DISPLAY 0.489362 (-4985 3390);
PAINT MONO (-4985 3390);
FORCEPROP 0 LASTPIN (-4925 3400) $PN DD15
R 1
J 2
(-4935 3390);
DISPLAY 0.489362 (-4935 3390);
PAINT MONO (-4935 3390);
FORCEPROP 0 LASTPIN (-4875 3400) $PN DD17
R 1
J 2
(-4885 3390);
DISPLAY 0.489362 (-4885 3390);
PAINT MONO (-4885 3390);
FORCEPROP 0 LASTPIN (-4825 3400) $PN DD19
R 1
J 2
(-4835 3390);
DISPLAY 0.489362 (-4835 3390);
PAINT MONO (-4835 3390);
FORCEPROP 0 LASTPIN (-4775 3400) $PN DD23
R 1
J 2
(-4785 3390);
DISPLAY 0.489362 (-4785 3390);
PAINT MONO (-4785 3390);
FORCEPROP 0 LASTPIN (-4725 3400) $PN DD24
R 1
J 2
(-4735 3390);
DISPLAY 0.489362 (-4735 3390);
PAINT MONO (-4735 3390);
FORCEPROP 0 LASTPIN (-4675 3400) $PN DD26
R 1
J 2
(-4685 3390);
DISPLAY 0.489362 (-4685 3390);
PAINT MONO (-4685 3390);
FORCEPROP 0 LASTPIN (-4625 3400) $PN DD27
R 1
J 2
(-4635 3390);
DISPLAY 0.489362 (-4635 3390);
PAINT MONO (-4635 3390);
FORCEPROP 0 LASTPIN (-4575 3400) $PN DD29
R 1
J 2
(-4585 3390);
DISPLAY 0.489362 (-4585 3390);
PAINT MONO (-4585 3390);
FORCEPROP 0 LASTPIN (-4525 3400) $PN DD30
R 1
J 2
(-4535 3390);
DISPLAY 0.489362 (-4535 3390);
PAINT MONO (-4535 3390);
FORCEPROP 0 LASTPIN (-4475 3400) $PN DD32
R 1
J 2
(-4485 3390);
DISPLAY 0.489362 (-4485 3390);
PAINT MONO (-4485 3390);
FORCEPROP 0 LASTPIN (-4425 3400) $PN DD33
R 1
J 2
(-4435 3390);
DISPLAY 0.489362 (-4435 3390);
PAINT MONO (-4435 3390);
FORCEPROP 0 LASTPIN (-4375 3400) $PN DD35
R 1
J 2
(-4385 3390);
DISPLAY 0.489362 (-4385 3390);
PAINT MONO (-4385 3390);
FORCEPROP 0 LASTPIN (-4325 3400) $PN DD36
R 1
J 2
(-4335 3390);
DISPLAY 0.489362 (-4335 3390);
PAINT MONO (-4335 3390);
FORCEPROP 0 LASTPIN (-4275 3400) $PN DD37
R 1
J 2
(-4285 3390);
DISPLAY 0.489362 (-4285 3390);
PAINT MONO (-4285 3390);
FORCEPROP 0 LASTPIN (-4225 3400) $PN DD39
R 1
J 2
(-4235 3390);
DISPLAY 0.489362 (-4235 3390);
PAINT MONO (-4235 3390);
FORCEPROP 0 LASTPIN (-4175 3400) $PN DD40
R 1
J 2
(-4185 3390);
DISPLAY 0.489362 (-4185 3390);
PAINT MONO (-4185 3390);
FORCEPROP 0 LASTPIN (-4125 3400) $PN DD41
R 1
J 2
(-4135 3390);
DISPLAY 0.489362 (-4135 3390);
PAINT MONO (-4135 3390);
FORCEPROP 0 LASTPIN (-4075 3400) $PN DD43
R 1
J 2
(-4085 3390);
DISPLAY 0.489362 (-4085 3390);
PAINT MONO (-4085 3390);
FORCEPROP 0 LASTPIN (-4025 3400) $PN DD44
R 1
J 2
(-4035 3390);
DISPLAY 0.489362 (-4035 3390);
PAINT MONO (-4035 3390);
FORCEPROP 0 LASTPIN (-3975 3400) $PN DD46
R 1
J 2
(-3985 3390);
DISPLAY 0.489362 (-3985 3390);
PAINT MONO (-3985 3390);
FORCEPROP 0 LASTPIN (-3925 3400) $PN DD47
R 1
J 2
(-3935 3390);
DISPLAY 0.489362 (-3935 3390);
PAINT MONO (-3935 3390);
FORCEPROP 0 LASTPIN (-3875 3400) $PN DD49
R 1
J 2
(-3885 3390);
DISPLAY 0.489362 (-3885 3390);
PAINT MONO (-3885 3390);
FORCEPROP 0 LASTPIN (-3825 3400) $PN DD50
R 1
J 2
(-3835 3390);
DISPLAY 0.489362 (-3835 3390);
PAINT MONO (-3835 3390);
FORCEPROP 0 LASTPIN (-3775 3400) $PN DD52
R 1
J 2
(-3785 3390);
DISPLAY 0.489362 (-3785 3390);
PAINT MONO (-3785 3390);
FORCEPROP 0 LASTPIN (-3725 3400) $PN DD53
R 1
J 2
(-3735 3390);
DISPLAY 0.489362 (-3735 3390);
PAINT MONO (-3735 3390);
FORCEPROP 0 LASTPIN (-3675 3400) $PN DD57
R 1
J 2
(-3685 3390);
DISPLAY 0.489362 (-3685 3390);
PAINT MONO (-3685 3390);
FORCEPROP 0 LASTPIN (-3625 3400) $PN DD59
R 1
J 2
(-3635 3390);
DISPLAY 0.489362 (-3635 3390);
PAINT MONO (-3635 3390);
FORCEPROP 0 LASTPIN (-3575 3400) $PN DD61
R 1
J 2
(-3585 3390);
DISPLAY 0.489362 (-3585 3390);
PAINT MONO (-3585 3390);
FORCEPROP 0 LASTPIN (-3525 3400) $PN DD64
R 1
J 2
(-3535 3390);
DISPLAY 0.489362 (-3535 3390);
PAINT MONO (-3535 3390);
FORCEPROP 0 LASTPIN (-3475 3400) $PN DD66
R 1
J 2
(-3485 3390);
DISPLAY 0.489362 (-3485 3390);
PAINT MONO (-3485 3390);
FORCEPROP 0 LASTPIN (-3425 3400) $PN DD68
R 1
J 2
(-3435 3390);
DISPLAY 0.489362 (-3435 3390);
PAINT MONO (-3435 3390);
FORCEPROP 0 LASTPIN (-3375 3400) $PN DD71
R 1
J 2
(-3385 3390);
DISPLAY 0.489362 (-3385 3390);
PAINT MONO (-3385 3390);
FORCEPROP 0 LASTPIN (-3325 3400) $PN DD73
R 1
J 2
(-3335 3390);
DISPLAY 0.489362 (-3335 3390);
PAINT MONO (-3335 3390);
FORCEPROP 0 LASTPIN (-3275 3400) $PN DE1
R 1
J 2
(-3285 3390);
DISPLAY 0.489362 (-3285 3390);
PAINT MONO (-3285 3390);
FORCEPROP 0 LASTPIN (-3225 3400) $PN DE6
R 1
J 2
(-3235 3390);
DISPLAY 0.489362 (-3235 3390);
PAINT MONO (-3235 3390);
FORCEPROP 0 LASTPIN (-3175 3400) $PN DE8
R 1
J 2
(-3185 3390);
DISPLAY 0.489362 (-3185 3390);
PAINT MONO (-3185 3390);
FORCEPROP 0 LASTPIN (-3125 3400) $PN DE13
R 1
J 2
(-3135 3390);
DISPLAY 0.489362 (-3135 3390);
PAINT MONO (-3135 3390);
FORCEPROP 0 LASTPIN (-3075 3400) $PN DE15
R 1
J 2
(-3085 3390);
DISPLAY 0.489362 (-3085 3390);
PAINT MONO (-3085 3390);
FORCEPROP 0 LASTPIN (-3025 3400) $PN DE20
R 1
J 2
(-3035 3390);
DISPLAY 0.489362 (-3035 3390);
PAINT MONO (-3035 3390);
FORCEPROP 0 LASTPIN (-2975 3400) $PN DE23
R 1
J 2
(-2985 3390);
DISPLAY 0.489362 (-2985 3390);
PAINT MONO (-2985 3390);
FORCEPROP 0 LASTPIN (-2925 3400) $PN DE26
R 1
J 2
(-2935 3390);
DISPLAY 0.489362 (-2935 3390);
PAINT MONO (-2935 3390);
FORCEPROP 0 LASTPIN (-2875 3400) $PN DE29
R 1
J 2
(-2885 3390);
DISPLAY 0.489362 (-2885 3390);
PAINT MONO (-2885 3390);
FORCEPROP 0 LASTPIN (-2825 3400) $PN DE33
R 1
J 2
(-2835 3390);
DISPLAY 0.489362 (-2835 3390);
PAINT MONO (-2835 3390);
FORCEPROP 0 LASTPIN (-2775 3400) $PN DE56
R 1
J 2
(-2785 3390);
DISPLAY 0.489362 (-2785 3390);
PAINT MONO (-2785 3390);
FORCEPROP 0 LASTPIN (-2725 3400) $PN DE61
R 1
J 2
(-2735 3390);
DISPLAY 0.489362 (-2735 3390);
PAINT MONO (-2735 3390);
FORCEPROP 0 LASTPIN (-2675 3400) $PN DE63
R 1
J 2
(-2685 3390);
DISPLAY 0.489362 (-2685 3390);
PAINT MONO (-2685 3390);
FORCEPROP 0 LASTPIN (-2625 3400) $PN DE68
R 1
J 2
(-2635 3390);
DISPLAY 0.489362 (-2635 3390);
PAINT MONO (-2635 3390);
FORCEPROP 0 LASTPIN (-2575 3400) $PN DE70
R 1
J 2
(-2585 3390);
DISPLAY 0.489362 (-2585 3390);
PAINT MONO (-2585 3390);
FORCEPROP 0 LASTPIN (-2525 3400) $PN DE75
R 1
J 2
(-2535 3390);
DISPLAY 0.489362 (-2535 3390);
PAINT MONO (-2535 3390);
FORCEPROP 0 LASTPIN (-2475 3400) $PN DF3
R 1
J 2
(-2485 3390);
DISPLAY 0.489362 (-2485 3390);
PAINT MONO (-2485 3390);
FORCEPROP 0 LASTPIN (-2425 3400) $PN DF4
R 1
J 2
(-2435 3390);
DISPLAY 0.489362 (-2435 3390);
PAINT MONO (-2435 3390);
FORCEPROP 0 LASTPIN (-2375 3400) $PN DF5
R 1
J 2
(-2385 3390);
DISPLAY 0.489362 (-2385 3390);
PAINT MONO (-2385 3390);
FORCEPROP 0 LASTPIN (-2325 3400) $PN DF6
R 1
J 2
(-2335 3390);
DISPLAY 0.489362 (-2335 3390);
PAINT MONO (-2335 3390);
FORCEPROP 0 LASTPIN (-2275 3400) $PN DF8
R 1
J 2
(-2285 3390);
DISPLAY 0.489362 (-2285 3390);
PAINT MONO (-2285 3390);
FORCEPROP 0 LASTPIN (-2225 3400) $PN DF10
R 1
J 2
(-2235 3390);
DISPLAY 0.489362 (-2235 3390);
PAINT MONO (-2235 3390);
FORCEPROP 0 LASTPIN (-2175 3400) $PN DF11
R 1
J 2
(-2185 3390);
DISPLAY 0.489362 (-2185 3390);
PAINT MONO (-2185 3390);
FORCEPROP 0 LASTPIN (-2125 3400) $PN DF12
R 1
J 2
(-2135 3390);
DISPLAY 0.489362 (-2135 3390);
PAINT MONO (-2135 3390);
FORCEPROP 0 LASTPIN (-2075 3400) $PN DF13
R 1
J 2
(-2085 3390);
DISPLAY 0.489362 (-2085 3390);
PAINT MONO (-2085 3390);
FORCEPROP 0 LASTPIN (-2025 3400) $PN DF15
R 1
J 2
(-2035 3390);
DISPLAY 0.489362 (-2035 3390);
PAINT MONO (-2035 3390);
FORCEPROP 0 LASTPIN (-1975 3400) $PN DF17
R 1
J 2
(-1985 3390);
DISPLAY 0.489362 (-1985 3390);
PAINT MONO (-1985 3390);
FORCEPROP 0 LASTPIN (-1925 3400) $PN DF18
R 1
J 2
(-1935 3390);
DISPLAY 0.489362 (-1935 3390);
PAINT MONO (-1935 3390);
FORCEPROP 0 LASTPIN (-1875 3400) $PN DF19
R 1
J 2
(-1885 3390);
DISPLAY 0.489362 (-1885 3390);
PAINT MONO (-1885 3390);
FORCEPROP 0 LASTPIN (-7775 4500) $PN DF20
R 1
J 0
(-7785 4510);
DISPLAY 0.489362 (-7785 4510);
PAINT MONO (-7785 4510);
FORCEPROP 0 LASTPIN (-7725 4500) $PN DF22
R 1
J 0
(-7735 4510);
DISPLAY 0.489362 (-7735 4510);
PAINT MONO (-7735 4510);
FORCEPROP 0 LASTPIN (-7675 4500) $PN DF23
R 1
J 0
(-7685 4510);
DISPLAY 0.489362 (-7685 4510);
PAINT MONO (-7685 4510);
FORCEPROP 0 LASTPIN (-7625 4500) $PN DF26
R 1
J 0
(-7635 4510);
DISPLAY 0.489362 (-7635 4510);
PAINT MONO (-7635 4510);
FORCEPROP 0 LASTPIN (-7575 4500) $PN DF29
R 1
J 0
(-7585 4510);
DISPLAY 0.489362 (-7585 4510);
PAINT MONO (-7585 4510);
FORCEPROP 0 LASTPIN (-7525 4500) $PN DF32
R 1
J 0
(-7535 4510);
DISPLAY 0.489362 (-7535 4510);
PAINT MONO (-7535 4510);
FORCEPROP 0 LASTPIN (-7475 4500) $PN DF35
R 1
J 0
(-7485 4510);
DISPLAY 0.489362 (-7485 4510);
PAINT MONO (-7485 4510);
FORCEPROP 0 LASTPIN (-7425 4500) $PN DF37
R 1
J 0
(-7435 4510);
DISPLAY 0.489362 (-7435 4510);
PAINT MONO (-7435 4510);
FORCEPROP 0 LASTPIN (-7375 4500) $PN DF39
R 1
J 0
(-7385 4510);
DISPLAY 0.489362 (-7385 4510);
PAINT MONO (-7385 4510);
FORCEPROP 0 LASTPIN (-7325 4500) $PN DF42
R 1
J 0
(-7335 4510);
DISPLAY 0.489362 (-7335 4510);
PAINT MONO (-7335 4510);
FORCEPROP 0 LASTPIN (-7275 4500) $PN DF43
R 1
J 0
(-7285 4510);
DISPLAY 0.489362 (-7285 4510);
PAINT MONO (-7285 4510);
FORCEPROP 0 LASTPIN (-7225 4500) $PN DF44
R 1
J 0
(-7235 4510);
DISPLAY 0.489362 (-7235 4510);
PAINT MONO (-7235 4510);
FORCEPROP 0 LASTPIN (-7175 4500) $PN DF45
R 1
J 0
(-7185 4510);
DISPLAY 0.489362 (-7185 4510);
PAINT MONO (-7185 4510);
FORCEPROP 0 LASTPIN (-7125 4500) $PN DF46
R 1
J 0
(-7135 4510);
DISPLAY 0.489362 (-7135 4510);
PAINT MONO (-7135 4510);
FORCEPROP 0 LASTPIN (-7075 4500) $PN DF47
R 1
J 0
(-7085 4510);
DISPLAY 0.489362 (-7085 4510);
PAINT MONO (-7085 4510);
FORCEPROP 0 LASTPIN (-7025 4500) $PN DF48
R 1
J 0
(-7035 4510);
DISPLAY 0.489362 (-7035 4510);
PAINT MONO (-7035 4510);
FORCEPROP 0 LASTPIN (-6975 4500) $PN DF49
R 1
J 0
(-6985 4510);
DISPLAY 0.489362 (-6985 4510);
PAINT MONO (-6985 4510);
FORCEPROP 0 LASTPIN (-6925 4500) $PN DF50
R 1
J 0
(-6935 4510);
DISPLAY 0.489362 (-6935 4510);
PAINT MONO (-6935 4510);
FORCEPROP 0 LASTPIN (-6875 4500) $PN DF51
R 1
J 0
(-6885 4510);
DISPLAY 0.489362 (-6885 4510);
PAINT MONO (-6885 4510);
FORCEPROP 0 LASTPIN (-6825 4500) $PN DF52
R 1
J 0
(-6835 4510);
DISPLAY 0.489362 (-6835 4510);
PAINT MONO (-6835 4510);
FORCEPROP 0 LASTPIN (-6775 4500) $PN DF53
R 1
J 0
(-6785 4510);
DISPLAY 0.489362 (-6785 4510);
PAINT MONO (-6785 4510);
FORCEPROP 0 LASTPIN (-6725 4500) $PN DF54
R 1
J 0
(-6735 4510);
DISPLAY 0.489362 (-6735 4510);
PAINT MONO (-6735 4510);
FORCEPROP 0 LASTPIN (-6675 4500) $PN DF56
R 1
J 0
(-6685 4510);
DISPLAY 0.489362 (-6685 4510);
PAINT MONO (-6685 4510);
FORCEPROP 0 LASTPIN (-6625 4500) $PN DF57
R 1
J 0
(-6635 4510);
DISPLAY 0.489362 (-6635 4510);
PAINT MONO (-6635 4510);
FORCEPROP 0 LASTPIN (-6575 4500) $PN DF58
R 1
J 0
(-6585 4510);
DISPLAY 0.489362 (-6585 4510);
PAINT MONO (-6585 4510);
FORCEPROP 0 LASTPIN (-6525 4500) $PN DF59
R 1
J 0
(-6535 4510);
DISPLAY 0.489362 (-6535 4510);
PAINT MONO (-6535 4510);
FORCEPROP 0 LASTPIN (-6475 4500) $PN DF61
R 1
J 0
(-6485 4510);
DISPLAY 0.489362 (-6485 4510);
PAINT MONO (-6485 4510);
FORCEPROP 0 LASTPIN (-6425 4500) $PN DF63
R 1
J 0
(-6435 4510);
DISPLAY 0.489362 (-6435 4510);
PAINT MONO (-6435 4510);
FORCEPROP 0 LASTPIN (-6375 4500) $PN DF64
R 1
J 0
(-6385 4510);
DISPLAY 0.489362 (-6385 4510);
PAINT MONO (-6385 4510);
FORCEPROP 0 LASTPIN (-6325 4500) $PN DF65
R 1
J 0
(-6335 4510);
DISPLAY 0.489362 (-6335 4510);
PAINT MONO (-6335 4510);
FORCEPROP 0 LASTPIN (-6275 4500) $PN DF66
R 1
J 0
(-6285 4510);
DISPLAY 0.489362 (-6285 4510);
PAINT MONO (-6285 4510);
FORCEPROP 0 LASTPIN (-6225 4500) $PN DF68
R 1
J 0
(-6235 4510);
DISPLAY 0.489362 (-6235 4510);
PAINT MONO (-6235 4510);
FORCEPROP 0 LASTPIN (-6175 4500) $PN DF70
R 1
J 0
(-6185 4510);
DISPLAY 0.489362 (-6185 4510);
PAINT MONO (-6185 4510);
FORCEPROP 0 LASTPIN (-6125 4500) $PN DF71
R 1
J 0
(-6135 4510);
DISPLAY 0.489362 (-6135 4510);
PAINT MONO (-6135 4510);
FORCEPROP 0 LASTPIN (-6075 4500) $PN DF72
R 1
J 0
(-6085 4510);
DISPLAY 0.489362 (-6085 4510);
PAINT MONO (-6085 4510);
FORCEPROP 0 LASTPIN (-6025 4500) $PN DF73
R 1
J 0
(-6035 4510);
DISPLAY 0.489362 (-6035 4510);
PAINT MONO (-6035 4510);
FORCEPROP 0 LASTPIN (-5975 4500) $PN DG1
R 1
J 0
(-5985 4510);
DISPLAY 0.489362 (-5985 4510);
PAINT MONO (-5985 4510);
FORCEPROP 0 LASTPIN (-5925 4500) $PN DG2
R 1
J 0
(-5935 4510);
DISPLAY 0.489362 (-5935 4510);
PAINT MONO (-5935 4510);
FORCEPROP 0 LASTPIN (-5875 4500) $PN DG6
R 1
J 0
(-5885 4510);
DISPLAY 0.489362 (-5885 4510);
PAINT MONO (-5885 4510);
FORCEPROP 0 LASTPIN (-5825 4500) $PN DG7
R 1
J 0
(-5835 4510);
DISPLAY 0.489362 (-5835 4510);
PAINT MONO (-5835 4510);
FORCEPROP 0 LASTPIN (-5775 4500) $PN DG8
R 1
J 0
(-5785 4510);
DISPLAY 0.489362 (-5785 4510);
PAINT MONO (-5785 4510);
FORCEPROP 0 LASTPIN (-5725 4500) $PN DG9
R 1
J 0
(-5735 4510);
DISPLAY 0.489362 (-5735 4510);
PAINT MONO (-5735 4510);
FORCEPROP 0 LASTPIN (-5675 4500) $PN DG13
R 1
J 0
(-5685 4510);
DISPLAY 0.489362 (-5685 4510);
PAINT MONO (-5685 4510);
FORCEPROP 0 LASTPIN (-5625 4500) $PN DG14
R 1
J 0
(-5635 4510);
DISPLAY 0.489362 (-5635 4510);
PAINT MONO (-5635 4510);
FORCEPROP 0 LASTPIN (-5575 4500) $PN DG15
R 1
J 0
(-5585 4510);
DISPLAY 0.489362 (-5585 4510);
PAINT MONO (-5585 4510);
FORCEPROP 0 LASTPIN (-5525 4500) $PN DG16
R 1
J 0
(-5535 4510);
DISPLAY 0.489362 (-5535 4510);
PAINT MONO (-5535 4510);
FORCEPROP 0 LASTPIN (-5475 4500) $PN DG18
R 1
J 0
(-5485 4510);
DISPLAY 0.489362 (-5485 4510);
PAINT MONO (-5485 4510);
FORCEPROP 0 LASTPIN (-5425 4500) $PN DG20
R 1
J 0
(-5435 4510);
DISPLAY 0.489362 (-5435 4510);
PAINT MONO (-5435 4510);
FORCEPROP 0 LASTPIN (-5375 4500) $PN DG21
R 1
J 0
(-5385 4510);
DISPLAY 0.489362 (-5385 4510);
PAINT MONO (-5385 4510);
FORCEPROP 0 LASTPIN (-5325 4500) $PN DG24
R 1
J 0
(-5335 4510);
DISPLAY 0.489362 (-5335 4510);
PAINT MONO (-5335 4510);
FORCEPROP 0 LASTPIN (-5275 4500) $PN DG27
R 1
J 0
(-5285 4510);
DISPLAY 0.489362 (-5285 4510);
PAINT MONO (-5285 4510);
FORCEPROP 0 LASTPIN (-5225 4500) $PN DG30
R 1
J 0
(-5235 4510);
DISPLAY 0.489362 (-5235 4510);
PAINT MONO (-5235 4510);
FORCEPROP 0 LASTPIN (-5175 4500) $PN DG33
R 1
J 0
(-5185 4510);
DISPLAY 0.489362 (-5185 4510);
PAINT MONO (-5185 4510);
FORCEPROP 0 LASTPIN (-5125 4500) $PN DG41
R 1
J 0
(-5135 4510);
DISPLAY 0.489362 (-5135 4510);
PAINT MONO (-5135 4510);
FORCEPROP 0 LASTPIN (-5075 4500) $PN DG43
R 1
J 0
(-5085 4510);
DISPLAY 0.489362 (-5085 4510);
PAINT MONO (-5085 4510);
FORCEPROP 0 LASTPIN (-5025 4500) $PN DG46
R 1
J 0
(-5035 4510);
DISPLAY 0.489362 (-5035 4510);
PAINT MONO (-5035 4510);
FORCEPROP 0 LASTPIN (-4975 4500) $PN DG49
R 1
J 0
(-4985 4510);
DISPLAY 0.489362 (-4985 4510);
PAINT MONO (-4985 4510);
FORCEPROP 0 LASTPIN (-4925 4500) $PN DG52
R 1
J 0
(-4935 4510);
DISPLAY 0.489362 (-4935 4510);
PAINT MONO (-4935 4510);
FORCEPROP 0 LASTPIN (-4875 4500) $PN DG55
R 1
J 0
(-4885 4510);
DISPLAY 0.489362 (-4885 4510);
PAINT MONO (-4885 4510);
FORCEPROP 0 LASTPIN (-4825 4500) $PN DG56
R 1
J 0
(-4835 4510);
DISPLAY 0.489362 (-4835 4510);
PAINT MONO (-4835 4510);
FORCEPROP 0 LASTPIN (-4775 4500) $PN DG59
R 1
J 0
(-4785 4510);
DISPLAY 0.489362 (-4785 4510);
PAINT MONO (-4785 4510);
FORCEPROP 0 LASTPIN (-4725 4500) $PN DG60
R 1
J 0
(-4735 4510);
DISPLAY 0.489362 (-4735 4510);
PAINT MONO (-4735 4510);
FORCEPROP 0 LASTPIN (-4675 4500) $PN DG61
R 1
J 0
(-4685 4510);
DISPLAY 0.489362 (-4685 4510);
PAINT MONO (-4685 4510);
FORCEPROP 0 LASTPIN (-4625 4500) $PN DG62
R 1
J 0
(-4635 4510);
DISPLAY 0.489362 (-4635 4510);
PAINT MONO (-4635 4510);
FORCEPROP 0 LASTPIN (-4575 4500) $PN DG63
R 1
J 0
(-4585 4510);
DISPLAY 0.489362 (-4585 4510);
PAINT MONO (-4585 4510);
FORCEPROP 0 LASTPIN (-4525 4500) $PN DG65
R 1
J 0
(-4535 4510);
DISPLAY 0.489362 (-4535 4510);
PAINT MONO (-4535 4510);
FORCEPROP 0 LASTPIN (-4475 4500) $PN DG66
R 1
J 0
(-4485 4510);
DISPLAY 0.489362 (-4485 4510);
PAINT MONO (-4485 4510);
FORCEPROP 0 LASTPIN (-4425 4500) $PN DG67
R 1
J 0
(-4435 4510);
DISPLAY 0.489362 (-4435 4510);
PAINT MONO (-4435 4510);
FORCEPROP 0 LASTPIN (-4375 4500) $PN DG68
R 1
J 0
(-4385 4510);
DISPLAY 0.489362 (-4385 4510);
PAINT MONO (-4385 4510);
FORCEPROP 0 LASTPIN (-4325 4500) $PN DG69
R 1
J 0
(-4335 4510);
DISPLAY 0.489362 (-4335 4510);
PAINT MONO (-4335 4510);
FORCEPROP 0 LASTPIN (-4275 4500) $PN DG70
R 1
J 0
(-4285 4510);
DISPLAY 0.489362 (-4285 4510);
PAINT MONO (-4285 4510);
FORCEPROP 0 LASTPIN (-4225 4500) $PN DG74
R 1
J 0
(-4235 4510);
DISPLAY 0.489362 (-4235 4510);
PAINT MONO (-4235 4510);
FORCEPROP 0 LASTPIN (-4175 4500) $PN DG75
R 1
J 0
(-4185 4510);
DISPLAY 0.489362 (-4185 4510);
PAINT MONO (-4185 4510);
FORCEPROP 0 LASTPIN (-4125 4500) $PN DH5
R 1
J 0
(-4135 4510);
DISPLAY 0.489362 (-4135 4510);
PAINT MONO (-4135 4510);
FORCEPROP 0 LASTPIN (-4075 4500) $PN DH11
R 1
J 0
(-4085 4510);
DISPLAY 0.489362 (-4085 4510);
PAINT MONO (-4085 4510);
FORCEPROP 0 LASTPIN (-4025 4500) $PN DH18
R 1
J 0
(-4035 4510);
DISPLAY 0.489362 (-4035 4510);
PAINT MONO (-4035 4510);
FORCEPROP 0 LASTPIN (-3975 4500) $PN DH37
R 1
J 0
(-3985 4510);
DISPLAY 0.489362 (-3985 4510);
PAINT MONO (-3985 4510);
FORCEPROP 0 LASTPIN (-3925 4500) $PN DH39
R 1
J 0
(-3935 4510);
DISPLAY 0.489362 (-3935 4510);
PAINT MONO (-3935 4510);
FORCEPROP 0 LASTPIN (-3875 4500) $PN DH43
R 1
J 0
(-3885 4510);
DISPLAY 0.489362 (-3885 4510);
PAINT MONO (-3885 4510);
FORCEPROP 0 LASTPIN (-3825 4500) $PN DH46
R 1
J 0
(-3835 4510);
DISPLAY 0.489362 (-3835 4510);
PAINT MONO (-3835 4510);
FORCEPROP 0 LASTPIN (-3775 4500) $PN DH49
R 1
J 0
(-3785 4510);
DISPLAY 0.489362 (-3785 4510);
PAINT MONO (-3785 4510);
FORCEPROP 0 LASTPIN (-3725 4500) $PN DH52
R 1
J 0
(-3735 4510);
DISPLAY 0.489362 (-3735 4510);
PAINT MONO (-3735 4510);
FORCEPROP 0 LASTPIN (-3675 4500) $PN DH55
R 1
J 0
(-3685 4510);
DISPLAY 0.489362 (-3685 4510);
PAINT MONO (-3685 4510);
FORCEPROP 0 LASTPIN (-3625 4500) $PN DH59
R 1
J 0
(-3635 4510);
DISPLAY 0.489362 (-3635 4510);
PAINT MONO (-3635 4510);
FORCEPROP 0 LASTPIN (-3575 4500) $PN DH61
R 1
J 0
(-3585 4510);
DISPLAY 0.489362 (-3585 4510);
PAINT MONO (-3585 4510);
FORCEPROP 0 LASTPIN (-3525 4500) $PN DH63
R 1
J 0
(-3535 4510);
DISPLAY 0.489362 (-3535 4510);
PAINT MONO (-3535 4510);
FORCEPROP 0 LASTPIN (-3475 4500) $PN DH64
R 1
J 0
(-3485 4510);
DISPLAY 0.489362 (-3485 4510);
PAINT MONO (-3485 4510);
FORCEPROP 0 LASTPIN (-3425 4500) $PN DH66
R 1
J 0
(-3435 4510);
DISPLAY 0.489362 (-3435 4510);
PAINT MONO (-3435 4510);
FORCEPROP 0 LASTPIN (-3375 4500) $PN DH68
R 1
J 0
(-3385 4510);
DISPLAY 0.489362 (-3385 4510);
PAINT MONO (-3385 4510);
FORCEPROP 0 LASTPIN (-3325 4500) $PN DH70
R 1
J 0
(-3335 4510);
DISPLAY 0.489362 (-3335 4510);
PAINT MONO (-3335 4510);
FORCEPROP 0 LASTPIN (-3275 4500) $PN DJ7
R 1
J 0
(-3285 4510);
DISPLAY 0.489362 (-3285 4510);
PAINT MONO (-3285 4510);
FORCEPROP 0 LASTPIN (-3225 4500) $PN DJ15
R 1
J 0
(-3235 4510);
DISPLAY 0.489362 (-3235 4510);
PAINT MONO (-3235 4510);
FORCEPROP 0 LASTPIN (-3175 4500) $PN DJ19
R 1
J 0
(-3185 4510);
DISPLAY 0.489362 (-3185 4510);
PAINT MONO (-3185 4510);
FORCEPROP 0 LASTPIN (-3125 4500) $PN DJ43
R 1
J 0
(-3135 4510);
DISPLAY 0.489362 (-3135 4510);
PAINT MONO (-3135 4510);
FORCEPROP 0 LASTPIN (-3075 4500) $PN DJ49
R 1
J 0
(-3085 4510);
DISPLAY 0.489362 (-3085 4510);
PAINT MONO (-3085 4510);
FORCEPROP 0 LASTPIN (-3025 4500) $PN DJ59
R 1
J 0
(-3035 4510);
DISPLAY 0.489362 (-3035 4510);
PAINT MONO (-3035 4510);
FORCEPROP 0 LASTPIN (-2975 4500) $PN DJ61
R 1
J 0
(-2985 4510);
DISPLAY 0.489362 (-2985 4510);
PAINT MONO (-2985 4510);
FORCEPROP 0 LASTPIN (-2925 4500) $PN DJ63
R 1
J 0
(-2935 4510);
DISPLAY 0.489362 (-2935 4510);
PAINT MONO (-2935 4510);
FORCEPROP 0 LASTPIN (-2875 4500) $PN DJ66
R 1
J 0
(-2885 4510);
DISPLAY 0.489362 (-2885 4510);
PAINT MONO (-2885 4510);
FORCEPROP 0 LASTPIN (-2825 4500) $PN DJ68
R 1
J 0
(-2835 4510);
DISPLAY 0.489362 (-2835 4510);
PAINT MONO (-2835 4510);
FORCEPROP 0 LASTPIN (-2775 4500) $PN DJ73
R 1
J 0
(-2785 4510);
DISPLAY 0.489362 (-2785 4510);
PAINT MONO (-2785 4510);
FORCEPROP 0 LASTPIN (-2725 4500) $PN K23
R 1
J 0
(-2735 4510);
DISPLAY 0.489362 (-2735 4510);
PAINT MONO (-2735 4510);
FORCEPROP 0 LASTPIN (-2675 4500) $PN K59
R 1
J 0
(-2685 4510);
DISPLAY 0.489362 (-2685 4510);
PAINT MONO (-2685 4510);
FORCEPROP 0 LASTPIN (-2625 4500) $PN P25
R 1
J 0
(-2635 4510);
DISPLAY 0.489362 (-2635 4510);
PAINT MONO (-2635 4510);
FORCEPROP 0 LASTPIN (-2575 4500) $PN P68
R 1
J 0
(-2585 4510);
DISPLAY 0.489362 (-2585 4510);
PAINT MONO (-2585 4510);
FORCEPROP 0 LASTPIN (-2525 4500) $PN V27
R 1
J 0
(-2535 4510);
DISPLAY 0.489362 (-2535 4510);
PAINT MONO (-2535 4510);
FORCEPROP 0 LASTPIN (-2475 4500) $PN V68
R 1
J 0
(-2485 4510);
DISPLAY 0.489362 (-2485 4510);
PAINT MONO (-2485 4510);
FORCEPROP 2 LAST PART_TYPE SMLF
R 1
J 0
(-8300 3550);
DISPLAY 1.021277 (-8300 3550);
FORCEPROP 1 LAST MATERIAL IO
R 1
J 0
(-7907 3555);
DISPLAY 0.489362 (-7907 3555);
PAINT SKYBLUE (-7907 3555);
FORCEPROP 2 LAST VALUE SOCKET6096_13568-001
R 1
J 0
(-7975 3550);
DISPLAY 0.489362 (-7975 3550);
PAINT SKYBLUE (-7975 3550);
FORCEPROP 2 LAST CDS_LIB pure_quanta
J 0
(-4525 3950);
DISPLAY INVISIBLE (-4525 3950);
FORCEPROP 1 LAST CDS_LMAN_SYM_OUTLINE -400,3350,400,-3350
R 1
J 0
(-4525 3950);
DISPLAY 0.468085 (-4525 3950);
PAINT GREEN (-4525 3950);
DISPLAY INVISIBLE (-4525 3950);
FORCEPROP 1 LAST NEEDS_NO_SIZE TRUE
R 1
J 0
(-4525 3950);
DISPLAY 0.723404 (-4525 3950);
PAINT GREEN (-4525 3950);
DISPLAY INVISIBLE (-4525 3950);
FORCEPROP 1 LAST PATH I3
R 1
J 0
(-4525 3950);
DISPLAY 0.723404 (-4525 3950);
PAINT GREEN (-4525 3950);
DISPLAY INVISIBLE (-4525 3950);
FORCEPROP 1 LAST PART_NUMBER DGA^6000030
R 1
J 0
(-8034 3555);
DISPLAY 0.489362 (-8034 3555);
PAINT SKYBLUE (-8034 3555);
DISPLAY INVISIBLE (-8034 3555);
FORCEADD QUANTA_TITLE_BLOCK_C..1
(-100 100);
FORCEPROP 0 LAST CDS_CON_LAST_MODIFIED Thu Sep 14 16:12:02 2023
J 0
(-1985 115);
DISPLAY INVISIBLE (-1985 115);
FORCEPROP 1 LAST CUSTOM_TXT_CDS <CON_LAST_MODIFIED>
J 0
(-1985 115);
DISPLAY 0.978723 (-1985 115);
FORCEPROP 2 LAST CUSTOM_TXT_CDS <XR_PAGE_TITLE>
J 0
(-7990 5350);
DISPLAY 0.638298 (-7990 5350);
PAINT PINK (-7990 5350);
DISPLAY INVISIBLE (-7990 5350);
FORCEPROP 1 LAST CUSTOM_TXT_CDS <NAME_2>
J 0
(-3275 150);
FORCEPROP 1 LAST CUSTOM_TXT_CDS <NAME_1>
J 0
(-3275 275);
FORCEPROP 1 LAST CUSTOM_TXT_CDS <Q_NUMBER>
J 0
(-1503 203);
DISPLAY 1.212766 (-1503 203);
FORCEPROP 1 LAST CUSTOM_TXT_CDS <Q_PROJ>
J 0
(-2482 202);
DISPLAY 1.212766 (-2482 202);
FORCEPROP 1 LAST CUSTOM_TXT_CDS <Q_REV>
J 0
(-284 203);
DISPLAY 1.212766 (-284 203);
FORCEPROP 1 LAST CUSTOM_TXT_CDS <CON_PAGE_NUM> OF <CON_TOTAL_PAGES>
J 0
(-546 118);
DISPLAY 0.978723 (-546 118);
FORCEPROP 1 LAST Q_TITLE CPU1 VSS 3/3
J 0
(-9400 150);
DISPLAY 2.446809 (-9400 150);
PAINT GREEN (-9400 150);
FORCEPROP 2 LAST CDS_LIB pure_quanta
J 0
(-100 100);
DISPLAY INVISIBLE (-100 100);
FORCEPROP 1 LAST CDS_LMAN_SYM_OUTLINE -9475,6775,100,-125
J 0
(-100 100);
DISPLAY 0.468085 (-100 100);
PAINT GREEN (-100 100);
DISPLAY INVISIBLE (-100 100);
FORCEPROP 2 LAST PAGE_BORDER TRUE
J 0
(-7990 5350);
DISPLAY 0.638298 (-7990 5350);
PAINT PINK (-7990 5350);
DISPLAY INVISIBLE (-7990 5350);
FORCEPROP 2 LAST CDS_XR_PAGE_TITLE CR-60 : @T6G_MB_LIB.T6G(SCH_1):PAGE60
J 0
(-7990 5350);
DISPLAY 0.638298 (-7990 5350);
PAINT PINK (-7990 5350);
DISPLAY INVISIBLE (-7990 5350);
FORCEPROP 1 LAST Q_DEPT BU9
J 1
(-3863 149);
DISPLAY 1.957447 (-3863 149);
PAINT GREEN (-3863 149);
DISPLAY INVISIBLE (-3863 149);
FORCEPROP 1 LAST COMMENT_BODY TRUE
J 0
(-88 87);
DISPLAY 0.978723 (-88 87);
PAINT GREEN (-88 87);
DISPLAY INVISIBLE (-88 87);
WIRE 16 -1 (-1875 3400)(-1875 3225);
WIRE 16 -1 (-1700 3225)(-1875 3225);
WIRE 16 -1 (-1875 3225)(-1925 3225);
WIRE 16 -1 (-1925 3400)(-1925 3225);
WIRE 16 -1 (-1975 3225)(-1925 3225);
WIRE 16 -1 (-1975 3400)(-1975 3225);
WIRE 16 -1 (-2025 3225)(-1975 3225);
WIRE 16 -1 (-2025 3400)(-2025 3225);
WIRE 16 -1 (-2075 3225)(-2025 3225);
WIRE 16 -1 (-2075 3400)(-2075 3225);
WIRE 16 -1 (-2125 3225)(-2075 3225);
WIRE 16 -1 (-2125 3400)(-2125 3225);
WIRE 16 -1 (-2175 3225)(-2125 3225);
WIRE 16 -1 (-2175 3225)(-2175 3400);
WIRE 16 -1 (-2225 3225)(-2175 3225);
WIRE 16 -1 (-2225 3225)(-2225 3400);
WIRE 16 -1 (-2275 3225)(-2225 3225);
WIRE 16 -1 (-2275 3400)(-2275 3225);
WIRE 16 -1 (-2325 3225)(-2275 3225);
WIRE 16 -1 (-2325 3225)(-2325 3400);
WIRE 16 -1 (-2375 3225)(-2325 3225);
WIRE 16 -1 (-2375 3225)(-2375 3400);
WIRE 16 -1 (-2425 3225)(-2375 3225);
WIRE 16 -1 (-2425 3400)(-2425 3225);
WIRE 16 -1 (-2475 3225)(-2425 3225);
WIRE 16 -1 (-2475 3225)(-2475 3400);
WIRE 16 -1 (-2525 3225)(-2475 3225);
WIRE 16 -1 (-2525 3400)(-2525 3225);
WIRE 16 -1 (-2575 3225)(-2525 3225);
WIRE 16 -1 (-2575 3225)(-2575 3400);
WIRE 16 -1 (-2625 3225)(-2575 3225);
WIRE 16 -1 (-2625 3225)(-2625 3400);
WIRE 16 -1 (-2675 3225)(-2625 3225);
WIRE 16 -1 (-2675 3400)(-2675 3225);
WIRE 16 -1 (-2725 3225)(-2675 3225);
WIRE 16 -1 (-2725 3225)(-2725 3400);
WIRE 16 -1 (-2775 3225)(-2725 3225);
WIRE 16 -1 (-2775 3400)(-2775 3225);
WIRE 16 -1 (-2825 3225)(-2775 3225);
WIRE 16 -1 (-2825 3225)(-2825 3400);
WIRE 16 -1 (-2875 3225)(-2825 3225);
WIRE 16 -1 (-2875 3225)(-2875 3400);
WIRE 16 -1 (-2925 3225)(-2875 3225);
WIRE 16 -1 (-2925 3400)(-2925 3225);
WIRE 16 -1 (-2975 3225)(-2925 3225);
WIRE 16 -1 (-2975 3225)(-2975 3400);
WIRE 16 -1 (-3025 3225)(-2975 3225);
WIRE 16 -1 (-3025 3400)(-3025 3225);
WIRE 16 -1 (-3075 3225)(-3025 3225);
WIRE 16 -1 (-3075 3225)(-3075 3400);
WIRE 16 -1 (-3125 3225)(-3075 3225);
WIRE 16 -1 (-3125 3225)(-3125 3400);
WIRE 16 -1 (-3175 3225)(-3125 3225);
WIRE 16 -1 (-3175 3400)(-3175 3225);
WIRE 16 -1 (-3225 3225)(-3175 3225);
WIRE 16 -1 (-3225 3225)(-3225 3400);
WIRE 16 -1 (-3275 3225)(-3225 3225);
WIRE 16 -1 (-3275 3400)(-3275 3225);
WIRE 16 -1 (-3325 3225)(-3275 3225);
WIRE 16 -1 (-3325 3400)(-3325 3225);
WIRE 16 -1 (-3375 3225)(-3325 3225);
WIRE 16 -1 (-3375 3225)(-3375 3400);
WIRE 16 -1 (-3425 3225)(-3375 3225);
WIRE 16 -1 (-3425 3400)(-3425 3225);
WIRE 16 -1 (-3475 3225)(-3425 3225);
WIRE 16 -1 (-3475 3225)(-3475 3400);
WIRE 16 -1 (-3525 3225)(-3475 3225);
WIRE 16 -1 (-3525 3225)(-3525 3400);
WIRE 16 -1 (-3575 3225)(-3525 3225);
WIRE 16 -1 (-3575 3400)(-3575 3225);
WIRE 16 -1 (-3625 3225)(-3575 3225);
WIRE 16 -1 (-3625 3225)(-3625 3400);
WIRE 16 -1 (-3675 3225)(-3625 3225);
WIRE 16 -1 (-3675 3400)(-3675 3225);
WIRE 16 -1 (-3725 3225)(-3675 3225);
WIRE 16 -1 (-3725 3225)(-3725 3400);
WIRE 16 -1 (-3775 3225)(-3725 3225);
WIRE 16 -1 (-3775 3225)(-3775 3400);
WIRE 16 -1 (-3825 3225)(-3775 3225);
WIRE 16 -1 (-3825 3400)(-3825 3225);
WIRE 16 -1 (-3875 3225)(-3825 3225);
WIRE 16 -1 (-3875 3225)(-3875 3400);
WIRE 16 -1 (-3925 3225)(-3875 3225);
WIRE 16 -1 (-3925 3400)(-3925 3225);
WIRE 16 -1 (-3975 3225)(-3925 3225);
WIRE 16 -1 (-3975 3225)(-3975 3400);
WIRE 16 -1 (-4025 3225)(-3975 3225);
WIRE 16 -1 (-4025 3225)(-4025 3400);
WIRE 16 -1 (-4075 3225)(-4025 3225);
WIRE 16 -1 (-4075 3400)(-4075 3225);
WIRE 16 -1 (-4125 3225)(-4075 3225);
WIRE 16 -1 (-4125 3225)(-4125 3400);
WIRE 16 -1 (-4175 3225)(-4125 3225);
WIRE 16 -1 (-4175 3400)(-4175 3225);
WIRE 16 -1 (-4225 3225)(-4175 3225);
WIRE 16 -1 (-4225 3225)(-4225 3400);
WIRE 16 -1 (-4275 3225)(-4225 3225);
WIRE 16 -1 (-4275 3225)(-4275 3400);
WIRE 16 -1 (-4325 3225)(-4275 3225);
WIRE 16 -1 (-4325 3400)(-4325 3225);
WIRE 16 -1 (-4375 3225)(-4325 3225);
WIRE 16 -1 (-4375 3225)(-4375 3400);
WIRE 16 -1 (-4425 3225)(-4375 3225);
WIRE 16 -1 (-4425 3225)(-4425 3400);
WIRE 16 -1 (-4475 3225)(-4425 3225);
WIRE 16 -1 (-4475 3400)(-4475 3225);
WIRE 16 -1 (-4525 3225)(-4475 3225);
WIRE 16 -1 (-4525 3225)(-4525 3400);
WIRE 16 -1 (-4575 3225)(-4525 3225);
WIRE 16 -1 (-4575 3400)(-4575 3225);
WIRE 16 -1 (-4625 3225)(-4575 3225);
WIRE 16 -1 (-4625 3225)(-4625 3400);
WIRE 16 -1 (-4675 3225)(-4625 3225);
WIRE 16 -1 (-4675 3225)(-4675 3400);
WIRE 16 -1 (-4725 3225)(-4675 3225);
WIRE 16 -1 (-4725 3400)(-4725 3225);
WIRE 16 -1 (-4775 3225)(-4725 3225);
WIRE 16 -1 (-4775 3225)(-4775 3400);
WIRE 16 -1 (-4825 3225)(-4775 3225);
WIRE 16 -1 (-4825 3400)(-4825 3225);
WIRE 16 -1 (-4875 3225)(-4825 3225);
WIRE 16 -1 (-4875 3225)(-4875 3400);
WIRE 16 -1 (-4925 3225)(-4875 3225);
WIRE 16 -1 (-4925 3225)(-4925 3400);
WIRE 16 -1 (-4975 3225)(-4925 3225);
WIRE 16 -1 (-4975 3400)(-4975 3225);
WIRE 16 -1 (-5025 3225)(-4975 3225);
WIRE 16 -1 (-5025 3225)(-5025 3400);
WIRE 16 -1 (-5075 3225)(-5025 3225);
WIRE 16 -1 (-5075 3400)(-5075 3225);
WIRE 16 -1 (-5125 3225)(-5075 3225);
WIRE 16 -1 (-5125 3225)(-5125 3400);
WIRE 16 -1 (-5175 3225)(-5125 3225);
WIRE 16 -1 (-5175 3225)(-5175 3400);
WIRE 16 -1 (-5225 3225)(-5175 3225);
WIRE 16 -1 (-5225 3400)(-5225 3225);
WIRE 16 -1 (-5275 3225)(-5225 3225);
WIRE 16 -1 (-5275 3225)(-5275 3400);
WIRE 16 -1 (-5325 3225)(-5275 3225);
WIRE 16 -1 (-5325 3400)(-5325 3225);
WIRE 16 -1 (-5375 3225)(-5325 3225);
WIRE 16 -1 (-5375 3225)(-5375 3400);
WIRE 16 -1 (-5425 3225)(-5375 3225);
WIRE 16 -1 (-5425 3225)(-5425 3400);
WIRE 16 -1 (-5475 3225)(-5425 3225);
WIRE 16 -1 (-5475 3400)(-5475 3225);
WIRE 16 -1 (-5525 3225)(-5475 3225);
WIRE 16 -1 (-5525 3225)(-5525 3400);
WIRE 16 -1 (-5575 3225)(-5525 3225);
WIRE 16 -1 (-5575 3225)(-5575 3400);
WIRE 16 -1 (-5625 3225)(-5575 3225);
WIRE 16 -1 (-5625 3400)(-5625 3225);
WIRE 16 -1 (-5675 3225)(-5625 3225);
WIRE 16 -1 (-5675 3225)(-5675 3400);
WIRE 16 -1 (-5725 3225)(-5675 3225);
WIRE 16 -1 (-5725 3400)(-5725 3225);
WIRE 16 -1 (-5775 3225)(-5725 3225);
WIRE 16 -1 (-5775 3225)(-5775 3400);
WIRE 16 -1 (-5825 3225)(-5775 3225);
WIRE 16 -1 (-5825 3225)(-5825 3400);
WIRE 16 -1 (-5875 3225)(-5825 3225);
WIRE 16 -1 (-5875 3400)(-5875 3225);
WIRE 16 -1 (-5925 3225)(-5875 3225);
WIRE 16 -1 (-5925 3225)(-5925 3400);
WIRE 16 -1 (-5975 3225)(-5925 3225);
WIRE 16 -1 (-5975 3400)(-5975 3225);
WIRE 16 -1 (-6025 3225)(-5975 3225);
WIRE 16 -1 (-6025 3225)(-6025 3400);
WIRE 16 -1 (-6075 3225)(-6025 3225);
WIRE 16 -1 (-6075 3225)(-6075 3400);
WIRE 16 -1 (-6125 3225)(-6075 3225);
WIRE 16 -1 (-6125 3400)(-6125 3225);
WIRE 16 -1 (-6175 3225)(-6125 3225);
WIRE 16 -1 (-6175 3225)(-6175 3400);
WIRE 16 -1 (-6225 3225)(-6175 3225);
WIRE 16 -1 (-6225 3400)(-6225 3225);
WIRE 16 -1 (-6275 3225)(-6225 3225);
WIRE 16 -1 (-6275 3225)(-6275 3400);
WIRE 16 -1 (-6325 3225)(-6275 3225);
WIRE 16 -1 (-6325 3225)(-6325 3400);
WIRE 16 -1 (-6375 3225)(-6325 3225);
WIRE 16 -1 (-6375 3400)(-6375 3225);
WIRE 16 -1 (-6425 3225)(-6375 3225);
WIRE 16 -1 (-6425 3225)(-6425 3400);
WIRE 16 -1 (-6475 3225)(-6425 3225);
WIRE 16 -1 (-6475 3400)(-6475 3225);
WIRE 16 -1 (-6525 3225)(-6475 3225);
WIRE 16 -1 (-6525 3400)(-6525 3225);
WIRE 16 -1 (-6575 3225)(-6525 3225);
WIRE 16 -1 (-6575 3225)(-6575 3400);
WIRE 16 -1 (-6625 3225)(-6575 3225);
WIRE 16 -1 (-6625 3400)(-6625 3225);
WIRE 16 -1 (-6675 3225)(-6625 3225);
WIRE 16 -1 (-6675 3225)(-6675 3400);
WIRE 16 -1 (-6725 3225)(-6675 3225);
WIRE 16 -1 (-6725 3225)(-6725 3400);
WIRE 16 -1 (-6775 3225)(-6725 3225);
WIRE 16 -1 (-6775 3400)(-6775 3225);
WIRE 16 -1 (-6825 3225)(-6775 3225);
WIRE 16 -1 (-6825 3225)(-6825 3400);
WIRE 16 -1 (-6875 3225)(-6825 3225);
WIRE 16 -1 (-6875 3400)(-6875 3225);
WIRE 16 -1 (-6925 3225)(-6875 3225);
WIRE 16 -1 (-6925 3225)(-6925 3400);
WIRE 16 -1 (-6975 3225)(-6925 3225);
WIRE 16 -1 (-6975 3225)(-6975 3400);
WIRE 16 -1 (-7025 3225)(-6975 3225);
WIRE 16 -1 (-7025 3400)(-7025 3225);
WIRE 16 -1 (-7075 3225)(-7025 3225);
WIRE 16 -1 (-7075 3225)(-7075 3400);
WIRE 16 -1 (-7125 3225)(-7075 3225);
WIRE 16 -1 (-7125 3400)(-7125 3225);
WIRE 16 -1 (-7175 3225)(-7125 3225);
WIRE 16 -1 (-7175 3225)(-7175 3400);
WIRE 16 -1 (-7225 3225)(-7175 3225);
WIRE 16 -1 (-7225 3225)(-7225 3400);
WIRE 16 -1 (-7275 3225)(-7225 3225);
WIRE 16 -1 (-7275 3400)(-7275 3225);
WIRE 16 -1 (-7325 3225)(-7275 3225);
WIRE 16 -1 (-7325 3225)(-7325 3400);
WIRE 16 -1 (-7375 3225)(-7325 3225);
WIRE 16 -1 (-7375 3400)(-7375 3225);
WIRE 16 -1 (-7425 3225)(-7375 3225);
WIRE 16 -1 (-7425 3225)(-7425 3400);
WIRE 16 -1 (-7475 3225)(-7425 3225);
WIRE 16 -1 (-7475 3225)(-7475 3400);
WIRE 16 -1 (-7525 3225)(-7475 3225);
WIRE 16 -1 (-7525 3400)(-7525 3225);
WIRE 16 -1 (-7575 3225)(-7525 3225);
WIRE 16 -1 (-7575 3225)(-7575 3400);
WIRE 16 -1 (-7625 3225)(-7575 3225);
WIRE 16 -1 (-7625 3225)(-7625 3400);
WIRE 16 -1 (-7675 3225)(-7625 3225);
WIRE 16 -1 (-7675 3400)(-7675 3225);
WIRE 16 -1 (-7725 3225)(-7675 3225);
WIRE 16 -1 (-7725 3225)(-7725 3400);
WIRE 16 -1 (-7775 3225)(-7725 3225);
WIRE 16 -1 (-7775 3400)(-7775 3225);
WIRE 16 -1 (-1125 4675)(-1375 4675);
WIRE 16 -1 (-1375 4675)(-1425 4675);
WIRE 16 -1 (-1375 4675)(-1375 4500);
WIRE 16 -1 (-1425 4675)(-1475 4675);
WIRE 16 -1 (-1425 4675)(-1425 4500);
WIRE 16 -1 (-1475 4675)(-1525 4675);
WIRE 16 -1 (-1475 4675)(-1475 4500);
WIRE 16 -1 (-1525 4675)(-1525 4500);
WIRE 16 -1 (-1525 4675)(-1575 4675);
WIRE 16 -1 (-1575 4675)(-1625 4675);
WIRE 16 -1 (-1575 4500)(-1575 4675);
WIRE 16 -1 (-1625 4675)(-1675 4675);
WIRE 16 -1 (-1625 4500)(-1625 4675);
WIRE 16 -1 (-1675 4675)(-1725 4675);
WIRE 16 -1 (-1675 4500)(-1675 4675);
WIRE 16 -1 (-1725 4675)(-1775 4675);
WIRE 16 -1 (-1725 4500)(-1725 4675);
WIRE 16 -1 (-1775 4675)(-1825 4675);
WIRE 16 -1 (-1775 4500)(-1775 4675);
WIRE 16 -1 (-1825 4675)(-1875 4675);
WIRE 16 -1 (-1825 4500)(-1825 4675);
WIRE 16 -1 (-1875 4675)(-1925 4675);
WIRE 16 -1 (-1875 4500)(-1875 4675);
WIRE 16 -1 (-1975 4675)(-1925 4675);
WIRE 16 -1 (-1925 4500)(-1925 4675);
WIRE 16 -1 (-2025 4675)(-1975 4675);
WIRE 16 -1 (-1975 4500)(-1975 4675);
WIRE 16 -1 (-2025 4500)(-2025 4675);
WIRE 16 -1 (-2075 4675)(-2025 4675);
WIRE 16 -1 (-2125 4675)(-2075 4675);
WIRE 16 -1 (-2075 4500)(-2075 4675);
WIRE 16 -1 (-2175 4675)(-2125 4675);
WIRE 16 -1 (-2125 4500)(-2125 4675);
WIRE 16 -1 (-2225 4675)(-2175 4675);
WIRE 16 -1 (-2175 4500)(-2175 4675);
WIRE 16 -1 (-2275 4675)(-2225 4675);
WIRE 16 -1 (-2225 4500)(-2225 4675);
WIRE 16 -1 (-2325 4675)(-2275 4675);
WIRE 16 -1 (-2275 4500)(-2275 4675);
WIRE 16 -1 (-2375 4675)(-2325 4675);
WIRE 16 -1 (-2325 4500)(-2325 4675);
WIRE 16 -1 (-2425 4675)(-2375 4675);
WIRE 16 -1 (-2375 4500)(-2375 4675);
WIRE 16 -1 (-2475 4675)(-2425 4675);
WIRE 16 -1 (-2425 4500)(-2425 4675);
WIRE 16 -1 (-2525 4675)(-2475 4675);
WIRE 16 -1 (-2475 4500)(-2475 4675);
WIRE 16 -1 (-2525 4500)(-2525 4675);
WIRE 16 -1 (-2575 4675)(-2525 4675);
WIRE 16 -1 (-2625 4675)(-2575 4675);
WIRE 16 -1 (-2575 4500)(-2575 4675);
WIRE 16 -1 (-2675 4675)(-2625 4675);
WIRE 16 -1 (-2625 4500)(-2625 4675);
WIRE 16 -1 (-2725 4675)(-2675 4675);
WIRE 16 -1 (-2675 4500)(-2675 4675);
WIRE 16 -1 (-2775 4675)(-2725 4675);
WIRE 16 -1 (-2725 4500)(-2725 4675);
WIRE 16 -1 (-2825 4675)(-2775 4675);
WIRE 16 -1 (-2775 4500)(-2775 4675);
WIRE 16 -1 (-2875 4675)(-2825 4675);
WIRE 16 -1 (-2825 4500)(-2825 4675);
WIRE 16 -1 (-2925 4675)(-2875 4675);
WIRE 16 -1 (-2875 4500)(-2875 4675);
WIRE 16 -1 (-2975 4675)(-2925 4675);
WIRE 16 -1 (-2925 4500)(-2925 4675);
WIRE 16 -1 (-3025 4675)(-2975 4675);
WIRE 16 -1 (-2975 4500)(-2975 4675);
WIRE 16 -1 (-3025 4500)(-3025 4675);
WIRE 16 -1 (-3075 4675)(-3025 4675);
WIRE 16 -1 (-3125 4675)(-3075 4675);
WIRE 16 -1 (-3075 4500)(-3075 4675);
WIRE 16 -1 (-3175 4675)(-3125 4675);
WIRE 16 -1 (-3125 4500)(-3125 4675);
WIRE 16 -1 (-3225 4675)(-3175 4675);
WIRE 16 -1 (-3175 4500)(-3175 4675);
WIRE 16 -1 (-3275 4675)(-3225 4675);
WIRE 16 -1 (-3225 4500)(-3225 4675);
WIRE 16 -1 (-3325 4675)(-3275 4675);
WIRE 16 -1 (-3275 4500)(-3275 4675);
WIRE 16 -1 (-3375 4675)(-3325 4675);
WIRE 16 -1 (-3325 4500)(-3325 4675);
WIRE 16 -1 (-3425 4675)(-3375 4675);
WIRE 16 -1 (-3375 4500)(-3375 4675);
WIRE 16 -1 (-3475 4675)(-3425 4675);
WIRE 16 -1 (-3425 4500)(-3425 4675);
WIRE 16 -1 (-3525 4675)(-3475 4675);
WIRE 16 -1 (-3475 4500)(-3475 4675);
WIRE 16 -1 (-3575 4675)(-3525 4675);
WIRE 16 -1 (-3525 4500)(-3525 4675);
WIRE 16 -1 (-3575 4500)(-3575 4675);
WIRE 16 -1 (-3625 4675)(-3575 4675);
WIRE 16 -1 (-3675 4675)(-3625 4675);
WIRE 16 -1 (-3625 4500)(-3625 4675);
WIRE 16 -1 (-3725 4675)(-3675 4675);
WIRE 16 -1 (-3675 4500)(-3675 4675);
WIRE 16 -1 (-3775 4675)(-3725 4675);
WIRE 16 -1 (-3725 4500)(-3725 4675);
WIRE 16 -1 (-3825 4675)(-3775 4675);
WIRE 16 -1 (-3775 4500)(-3775 4675);
WIRE 16 -1 (-3875 4675)(-3825 4675);
WIRE 16 -1 (-3825 4500)(-3825 4675);
WIRE 16 -1 (-3925 4675)(-3875 4675);
WIRE 16 -1 (-3875 4500)(-3875 4675);
WIRE 16 -1 (-3975 4675)(-3925 4675);
WIRE 16 -1 (-3925 4500)(-3925 4675);
WIRE 16 -1 (-4025 4675)(-3975 4675);
WIRE 16 -1 (-3975 4500)(-3975 4675);
WIRE 16 -1 (-4075 4675)(-4025 4675);
WIRE 16 -1 (-4025 4500)(-4025 4675);
WIRE 16 -1 (-4075 4500)(-4075 4675);
WIRE 16 -1 (-4125 4675)(-4075 4675);
WIRE 16 -1 (-4175 4675)(-4125 4675);
WIRE 16 -1 (-4125 4500)(-4125 4675);
WIRE 16 -1 (-4225 4675)(-4175 4675);
WIRE 16 -1 (-4175 4500)(-4175 4675);
WIRE 16 -1 (-4275 4675)(-4225 4675);
WIRE 16 -1 (-4225 4500)(-4225 4675);
WIRE 16 -1 (-4325 4675)(-4275 4675);
WIRE 16 -1 (-4275 4500)(-4275 4675);
WIRE 16 -1 (-4375 4675)(-4325 4675);
WIRE 16 -1 (-4325 4500)(-4325 4675);
WIRE 16 -1 (-4425 4675)(-4375 4675);
WIRE 16 -1 (-4375 4500)(-4375 4675);
WIRE 16 -1 (-4475 4675)(-4425 4675);
WIRE 16 -1 (-4425 4500)(-4425 4675);
WIRE 16 -1 (-4525 4675)(-4475 4675);
WIRE 16 -1 (-4475 4500)(-4475 4675);
WIRE 16 -1 (-4575 4675)(-4525 4675);
WIRE 16 -1 (-4525 4500)(-4525 4675);
WIRE 16 -1 (-4575 4500)(-4575 4675);
WIRE 16 -1 (-4625 4675)(-4575 4675);
WIRE 16 -1 (-4675 4675)(-4625 4675);
WIRE 16 -1 (-4625 4500)(-4625 4675);
WIRE 16 -1 (-4725 4675)(-4675 4675);
WIRE 16 -1 (-4675 4500)(-4675 4675);
WIRE 16 -1 (-4775 4675)(-4725 4675);
WIRE 16 -1 (-4725 4500)(-4725 4675);
WIRE 16 -1 (-4825 4675)(-4775 4675);
WIRE 16 -1 (-4775 4500)(-4775 4675);
WIRE 16 -1 (-4875 4675)(-4825 4675);
WIRE 16 -1 (-4825 4500)(-4825 4675);
WIRE 16 -1 (-4925 4675)(-4875 4675);
WIRE 16 -1 (-4875 4500)(-4875 4675);
WIRE 16 -1 (-4975 4675)(-4925 4675);
WIRE 16 -1 (-4925 4500)(-4925 4675);
WIRE 16 -1 (-5025 4675)(-4975 4675);
WIRE 16 -1 (-4975 4500)(-4975 4675);
WIRE 16 -1 (-5075 4675)(-5025 4675);
WIRE 16 -1 (-5025 4500)(-5025 4675);
WIRE 16 -1 (-5075 4500)(-5075 4675);
WIRE 16 -1 (-5125 4675)(-5075 4675);
WIRE 16 -1 (-5175 4675)(-5125 4675);
WIRE 16 -1 (-5125 4500)(-5125 4675);
WIRE 16 -1 (-5225 4675)(-5175 4675);
WIRE 16 -1 (-5175 4500)(-5175 4675);
WIRE 16 -1 (-5275 4675)(-5225 4675);
WIRE 16 -1 (-5225 4500)(-5225 4675);
WIRE 16 -1 (-5325 4675)(-5275 4675);
WIRE 16 -1 (-5275 4500)(-5275 4675);
WIRE 16 -1 (-5375 4675)(-5325 4675);
WIRE 16 -1 (-5325 4500)(-5325 4675);
WIRE 16 -1 (-5425 4675)(-5375 4675);
WIRE 16 -1 (-5375 4500)(-5375 4675);
WIRE 16 -1 (-5475 4675)(-5425 4675);
WIRE 16 -1 (-5425 4500)(-5425 4675);
WIRE 16 -1 (-5525 4675)(-5475 4675);
WIRE 16 -1 (-5475 4500)(-5475 4675);
WIRE 16 -1 (-5575 4675)(-5525 4675);
WIRE 16 -1 (-5525 4500)(-5525 4675);
WIRE 16 -1 (-5625 4675)(-5575 4675);
WIRE 16 -1 (-5575 4500)(-5575 4675);
WIRE 16 -1 (-5625 4500)(-5625 4675);
WIRE 16 -1 (-5675 4675)(-5625 4675);
WIRE 16 -1 (-5725 4675)(-5675 4675);
WIRE 16 -1 (-5675 4500)(-5675 4675);
WIRE 16 -1 (-5775 4675)(-5725 4675);
WIRE 16 -1 (-5725 4500)(-5725 4675);
WIRE 16 -1 (-5825 4675)(-5775 4675);
WIRE 16 -1 (-5775 4500)(-5775 4675);
WIRE 16 -1 (-5875 4675)(-5825 4675);
WIRE 16 -1 (-5825 4500)(-5825 4675);
WIRE 16 -1 (-5925 4675)(-5875 4675);
WIRE 16 -1 (-5875 4500)(-5875 4675);
WIRE 16 -1 (-5975 4675)(-5925 4675);
WIRE 16 -1 (-5925 4500)(-5925 4675);
WIRE 16 -1 (-6025 4675)(-5975 4675);
WIRE 16 -1 (-5975 4500)(-5975 4675);
WIRE 16 -1 (-6075 4675)(-6025 4675);
WIRE 16 -1 (-6025 4500)(-6025 4675);
WIRE 16 -1 (-6125 4675)(-6075 4675);
WIRE 16 -1 (-6075 4500)(-6075 4675);
WIRE 16 -1 (-6125 4500)(-6125 4675);
WIRE 16 -1 (-6175 4675)(-6125 4675);
WIRE 16 -1 (-6225 4675)(-6175 4675);
WIRE 16 -1 (-6175 4500)(-6175 4675);
WIRE 16 -1 (-6275 4675)(-6225 4675);
WIRE 16 -1 (-6225 4500)(-6225 4675);
WIRE 16 -1 (-6325 4675)(-6275 4675);
WIRE 16 -1 (-6275 4500)(-6275 4675);
WIRE 16 -1 (-6375 4675)(-6325 4675);
WIRE 16 -1 (-6325 4500)(-6325 4675);
WIRE 16 -1 (-6425 4675)(-6375 4675);
WIRE 16 -1 (-6375 4500)(-6375 4675);
WIRE 16 -1 (-6475 4675)(-6425 4675);
WIRE 16 -1 (-6425 4500)(-6425 4675);
WIRE 16 -1 (-6525 4675)(-6475 4675);
WIRE 16 -1 (-6475 4500)(-6475 4675);
WIRE 16 -1 (-6575 4675)(-6525 4675);
WIRE 16 -1 (-6525 4500)(-6525 4675);
WIRE 16 -1 (-6625 4675)(-6575 4675);
WIRE 16 -1 (-6575 4500)(-6575 4675);
WIRE 16 -1 (-6625 4500)(-6625 4675);
WIRE 16 -1 (-6675 4675)(-6625 4675);
WIRE 16 -1 (-6725 4675)(-6675 4675);
WIRE 16 -1 (-6675 4500)(-6675 4675);
WIRE 16 -1 (-6775 4675)(-6725 4675);
WIRE 16 -1 (-6725 4500)(-6725 4675);
WIRE 16 -1 (-6825 4675)(-6775 4675);
WIRE 16 -1 (-6775 4500)(-6775 4675);
WIRE 16 -1 (-6875 4675)(-6825 4675);
WIRE 16 -1 (-6825 4500)(-6825 4675);
WIRE 16 -1 (-6925 4675)(-6875 4675);
WIRE 16 -1 (-6875 4500)(-6875 4675);
WIRE 16 -1 (-6975 4675)(-6925 4675);
WIRE 16 -1 (-6925 4500)(-6925 4675);
WIRE 16 -1 (-7025 4675)(-6975 4675);
WIRE 16 -1 (-6975 4500)(-6975 4675);
WIRE 16 -1 (-7075 4675)(-7025 4675);
WIRE 16 -1 (-7025 4500)(-7025 4675);
WIRE 16 -1 (-7125 4675)(-7075 4675);
WIRE 16 -1 (-7075 4500)(-7075 4675);
WIRE 16 -1 (-7125 4500)(-7125 4675);
WIRE 16 -1 (-7175 4675)(-7125 4675);
WIRE 16 -1 (-7225 4675)(-7175 4675);
WIRE 16 -1 (-7175 4500)(-7175 4675);
WIRE 16 -1 (-7275 4675)(-7225 4675);
WIRE 16 -1 (-7225 4500)(-7225 4675);
WIRE 16 -1 (-7325 4675)(-7275 4675);
WIRE 16 -1 (-7275 4500)(-7275 4675);
WIRE 16 -1 (-7375 4675)(-7325 4675);
WIRE 16 -1 (-7325 4500)(-7325 4675);
WIRE 16 -1 (-7425 4675)(-7375 4675);
WIRE 16 -1 (-7375 4500)(-7375 4675);
WIRE 16 -1 (-7475 4675)(-7425 4675);
WIRE 16 -1 (-7425 4500)(-7425 4675);
WIRE 16 -1 (-7525 4675)(-7475 4675);
WIRE 16 -1 (-7475 4500)(-7475 4675);
WIRE 16 -1 (-7575 4675)(-7525 4675);
WIRE 16 -1 (-7525 4500)(-7525 4675);
WIRE 16 -1 (-7625 4675)(-7575 4675);
WIRE 16 -1 (-7575 4500)(-7575 4675);
WIRE 16 -1 (-7675 4675)(-7625 4675);
WIRE 16 -1 (-7625 4500)(-7625 4675);
WIRE 16 -1 (-7675 4500)(-7675 4675);
WIRE 16 -1 (-7725 4675)(-7675 4675);
WIRE 16 -1 (-7775 4675)(-7725 4675);
WIRE 16 -1 (-7725 4500)(-7725 4675);
WIRE 16 -1 (-7775 4500)(-7775 4675);
DOT 1 (-4525 4675);
DOT 1 (-7725 3225);
DOT 1 (-7675 3225);
DOT 1 (-7625 3225);
DOT 1 (-7525 3225);
DOT 1 (-7475 3225);
DOT 1 (-7425 3225);
DOT 1 (-7375 3225);
DOT 1 (-7325 3225);
DOT 1 (-7275 3225);
DOT 1 (-7225 3225);
DOT 1 (-7175 3225);
DOT 1 (-7125 3225);
DOT 1 (-7075 3225);
DOT 1 (-7025 3225);
DOT 1 (-6975 3225);
DOT 1 (-6925 3225);
DOT 1 (-6875 3225);
DOT 1 (-6825 3225);
DOT 1 (-6775 3225);
DOT 1 (-6725 3225);
DOT 1 (-6675 3225);
DOT 1 (-6625 3225);
DOT 1 (-6575 3225);
DOT 1 (-6525 3225);
DOT 1 (-6475 3225);
DOT 1 (-6425 3225);
DOT 1 (-6375 3225);
DOT 1 (-6325 3225);
DOT 1 (-6275 3225);
DOT 1 (-6225 3225);
DOT 1 (-6175 3225);
DOT 1 (-6125 3225);
DOT 1 (-6075 3225);
DOT 1 (-6025 3225);
DOT 1 (-5975 3225);
DOT 1 (-5925 3225);
DOT 1 (-5875 3225);
DOT 1 (-5825 3225);
DOT 1 (-5775 3225);
DOT 1 (-5725 3225);
DOT 1 (-5675 3225);
DOT 1 (-5625 3225);
DOT 1 (-5575 3225);
DOT 1 (-5525 3225);
DOT 1 (-5475 3225);
DOT 1 (-5425 3225);
DOT 1 (-5375 3225);
DOT 1 (-5325 3225);
DOT 1 (-5275 3225);
DOT 1 (-5225 3225);
DOT 1 (-5175 3225);
DOT 1 (-5125 3225);
DOT 1 (-5075 3225);
DOT 1 (-5025 3225);
DOT 1 (-4975 3225);
DOT 1 (-4925 3225);
DOT 1 (-4875 3225);
DOT 1 (-4825 3225);
DOT 1 (-4775 3225);
DOT 1 (-4725 3225);
DOT 1 (-4675 3225);
DOT 1 (-4625 3225);
DOT 1 (-4575 3225);
DOT 1 (-4525 3225);
DOT 1 (-4475 3225);
DOT 1 (-4425 3225);
DOT 1 (-4375 3225);
DOT 1 (-4325 3225);
DOT 1 (-4275 3225);
DOT 1 (-4225 3225);
DOT 1 (-4175 3225);
DOT 1 (-4125 3225);
DOT 1 (-4075 3225);
DOT 1 (-4025 3225);
DOT 1 (-3975 3225);
DOT 1 (-3925 3225);
DOT 1 (-3875 3225);
DOT 1 (-7725 4675);
DOT 1 (-7675 4675);
DOT 1 (-7625 4675);
DOT 1 (-7575 4675);
DOT 1 (-7475 4675);
DOT 1 (-7525 4675);
DOT 1 (-7425 4675);
DOT 1 (-7375 4675);
DOT 1 (-7325 4675);
DOT 1 (-7225 4675);
DOT 1 (-7275 4675);
DOT 1 (-7075 4675);
DOT 1 (-7125 4675);
DOT 1 (-7175 4675);
DOT 1 (-7025 4675);
DOT 1 (-6975 4675);
DOT 1 (-6825 4675);
DOT 1 (-6875 4675);
DOT 1 (-6925 4675);
DOT 1 (-6775 4675);
DOT 1 (-6725 4675);
DOT 1 (-6675 4675);
DOT 1 (-6575 4675);
DOT 1 (-6625 4675);
DOT 1 (-6525 4675);
DOT 1 (-6475 4675);
DOT 1 (-6425 4675);
DOT 1 (-6325 4675);
DOT 1 (-6375 4675);
DOT 1 (-6275 4675);
DOT 1 (-6225 4675);
DOT 1 (-6175 4675);
DOT 1 (-6125 4675);
DOT 1 (-6075 4675);
DOT 1 (-5975 4675);
DOT 1 (-5925 4675);
DOT 1 (-6025 4675);
DOT 1 (-5875 4675);
DOT 1 (-5825 4675);
DOT 1 (-5725 4675);
DOT 1 (-5675 4675);
DOT 1 (-5775 4675);
DOT 1 (-5625 4675);
DOT 1 (-5575 4675);
DOT 1 (-5525 4675);
DOT 1 (-5425 4675);
DOT 1 (-5475 4675);
DOT 1 (-5375 4675);
DOT 1 (-5325 4675);
DOT 1 (-5275 4675);
DOT 1 (-5175 4675);
DOT 1 (-5225 4675);
DOT 1 (-5025 4675);
DOT 1 (-5075 4675);
DOT 1 (-5125 4675);
DOT 1 (-4975 4675);
DOT 1 (-4925 4675);
DOT 1 (-4775 4675);
DOT 1 (-4825 4675);
DOT 1 (-4875 4675);
DOT 1 (-4725 4675);
DOT 1 (-4675 4675);
DOT 1 (-4625 4675);
DOT 1 (-4575 4675);
DOT 1 (-4475 4675);
DOT 1 (-4425 4675);
DOT 1 (-4375 4675);
DOT 1 (-4275 4675);
DOT 1 (-4325 4675);
DOT 1 (-4225 4675);
DOT 1 (-4175 4675);
DOT 1 (-4125 4675);
DOT 1 (-4025 4675);
DOT 1 (-4075 4675);
DOT 1 (-3875 4675);
DOT 1 (-3925 4675);
DOT 1 (-3975 4675);
DOT 1 (-3825 3225);
DOT 1 (-3775 3225);
DOT 1 (-3725 3225);
DOT 1 (-3675 3225);
DOT 1 (-3625 3225);
DOT 1 (-3575 3225);
DOT 1 (-3525 3225);
DOT 1 (-3475 3225);
DOT 1 (-3425 3225);
DOT 1 (-3375 3225);
DOT 1 (-3275 3225);
DOT 1 (-3325 3225);
DOT 1 (-3225 3225);
DOT 1 (-3175 3225);
DOT 1 (-3125 3225);
DOT 1 (-3075 3225);
DOT 1 (-3025 3225);
DOT 1 (-2975 3225);
DOT 1 (-2925 3225);
DOT 1 (-2875 3225);
DOT 1 (-2825 3225);
DOT 1 (-2775 3225);
DOT 1 (-2725 3225);
DOT 1 (-2675 3225);
DOT 1 (-2625 3225);
DOT 1 (-2575 3225);
DOT 1 (-2525 3225);
DOT 1 (-2475 3225);
DOT 1 (-2425 3225);
DOT 1 (-2375 3225);
DOT 1 (-2325 3225);
DOT 1 (-2275 3225);
DOT 1 (-2225 3225);
DOT 1 (-2175 3225);
DOT 1 (-2125 3225);
DOT 1 (-2075 3225);
DOT 1 (-2025 3225);
DOT 1 (-1975 3225);
DOT 1 (-1925 3225);
DOT 1 (-1875 3225);
DOT 1 (-3825 4675);
DOT 1 (-3775 4675);
DOT 1 (-3675 4675);
DOT 1 (-3625 4675);
DOT 1 (-3725 4675);
DOT 1 (-3575 4675);
DOT 1 (-3525 4675);
DOT 1 (-3475 4675);
DOT 1 (-3375 4675);
DOT 1 (-3425 4675);
DOT 1 (-3275 4675);
DOT 1 (-3325 4675);
DOT 1 (-3225 4675);
DOT 1 (-3125 4675);
DOT 1 (-3175 4675);
DOT 1 (-3075 4675);
DOT 1 (-3025 4675);
DOT 1 (-2975 4675);
DOT 1 (-2925 4675);
DOT 1 (-2875 4675);
DOT 1 (-2725 4675);
DOT 1 (-2775 4675);
DOT 1 (-2825 4675);
DOT 1 (-2675 4675);
DOT 1 (-2625 4675);
DOT 1 (-2475 4675);
DOT 1 (-2525 4675);
DOT 1 (-2575 4675);
DOT 1 (-2425 4675);
DOT 1 (-2375 4675);
DOT 1 (-2325 4675);
DOT 1 (-2225 4675);
DOT 1 (-2275 4675);
DOT 1 (-2175 4675);
DOT 1 (-2125 4675);
DOT 1 (-2075 4675);
DOT 1 (-1975 4675);
DOT 1 (-2025 4675);
DOT 1 (-1825 4675);
DOT 1 (-1875 4675);
DOT 1 (-1925 4675);
DOT 1 (-1775 4675);
DOT 1 (-1725 4675);
DOT 1 (-1625 4675);
DOT 1 (-1575 4675);
DOT 1 (-1675 4675);
DOT 1 (-1525 4675);
DOT 1 (-1475 4675);
DOT 1 (-1425 4675);
DOT 1 (-1375 4675);
DOT 1 (-7575 3225);
QUIT
